Altium Designer Pick and Place Locations
C:\Users\<user>\Desktop\WorkNotes\Projects\PTP\TimeCardNPI\HackDesign\WIP\ECAD\Project Outputs for Timingcard_PROJECT\Pick Place for TimeCard-DC-V7_EXP.csv

========================================================================================================================
File Design Information:

Date:       21/11/22
Time:       09:17
Revision:   Not in VersionControl
Variant:    No variations
Units used: mil

"Designator","Comment","Layer","Footprint","Center-X(mil)","Center-Y(mil)","Rotation","Description"
"P1","AUX Sensor","TopLayer","HDR1X4","1573.622","-1200.787","180","Header, 4-Pin"
"R47","DNI_0_5%_1206","TopLayer","RESC3116X65X50ML20T20","3657.480","-1362.205","0",""
"J38","39-30-1060","TopLayer","39-30-1060","6492.126","-1779.528","90","CONN, HDR, 2X3, R/A, 4.2MM, TH, MINI-FIT JR"
"R46","DNI_0_5%_1206","TopLayer","RESC3116X65X50ML20T20","3417.323","-1248.032","180",""
"R45","0_5%_1206","TopLayer","RESC3116X65X50ML20T20","3649.606","-1248.032","0",""
"R44","DNI_0_5%_1206","TopLayer","RESC3116X65X50ML20T20","6480.315","-2602.362","180",""
"D19","STPS5L60S","TopLayer","FP-STPS5L60S-MFG","6728.346","-2767.716","270","DIODE SCHOTTKY 60V 5A SMC"
"D12","STPS5L60S","TopLayer","FP-STPS5L60S-MFG","6728.346","-2275.591","90","DIODE SCHOTTKY 60V 5A SMC"
"J37","Single FPGA Conn","TopLayer","SingleFPGAConn","4309.097","-3085.975","90",""
"J36","Single FPGA Conn","TopLayer","SingleFPGAConn","3409.043","-2340.449","0",""
"J35","Single FPGA Conn","TopLayer","SingleFPGAConn","4309.097","-1604.766","270",""
"J34","Single FPGA Conn","TopLayer","SingleFPGAConn","5283.953","-2340.449","180",""
"J31","SA53_Header","TopLayer","SA53_Header","3013.188","-2365.934","180",""
"J13","GNSS Header","TopLayer","SMTC-TLE-104-01-X-DV","6398.148","-258.362","270","8-pin GNSS header"
"J6","GNSS Header","TopLayer","SMTC-TLE-104-01-X-DV","836.105","-618.599","90","8-pin GNSS header"
"R43","DNI_49.9R","TopLayer","RESC1608X55X25NL10T15","2452.756","-1271.653","180","General Purpose Chip Resistor, 49.9 Ohm, +/- 1%, -55 to 155 degC, 0603 (1608 Metric), RoHS, Tape and Reel"
"R42","DNI_49.9R","TopLayer","RESC1608X55X25NL10T15","2600.503","-1322.773","180","General Purpose Chip Resistor, 49.9 Ohm, +/- 1%, -55 to 155 degC, 0603 (1608 Metric), RoHS, Tape and Reel"
"D10","BLUE","TopLayer","FP-LTST-C191TBKT-MFG","403.543","118.110","90","LED BLUE CLEAR CHIP SMD"
"D9","BLUE","TopLayer","FP-LTST-C191TBKT-MFG","334.646","118.110","90","LED BLUE CLEAR CHIP SMD"
"D3","BLUE","TopLayer","FP-LTST-C191TBKT-MFG","265.748","118.110","90","LED BLUE CLEAR CHIP SMD"
"U16","NC7WV125K8X","TopLayer","SOP50P310X90-8N","748.032","-3188.976","180","Integrated Circuit"
"U12","NC7WV125K8X","TopLayer","SOP50P310X90-8N","757.874","-2125.984","180","Integrated Circuit"
"U11","NC7WV125K8X","TopLayer","SOP50P310X90-8N","757.874","-2647.638","180","Integrated Circuit"
"U8","NC7WV125K8X","TopLayer","SOP50P310X90-8N","748.032","-1594.488","180","Integrated Circuit"
"U6","IS32FL3207","TopLayer","IS32FL3207","1033.465","-1259.842","0",""
"R41","4.7K","TopLayer","RESC1608X55X30NL15T15","797.244","-1358.268","0","Precision Thick Film Chip Resistor, 4.7 KOhm, +/- 1%, -55 to 155 degC, 0603 (1608 Metric), RoHS, Tape and Reel ERJ-3EKF4701V"
"R40","100k","TopLayer","FP-RC0603-0_55-MFG","826.772","-1131.890","270","RES SMD 100K OHM 1% 1/10W 0603"
"R39","200 OHM","TopLayer","RESC1608X55X30NL15T15","472.441","-19.685","90","ERJ-3EKF2000V"
"R38","200 OHM","TopLayer","RESC1608X55X30NL15T15","403.543","-19.685","90","ERJ-3EKF2000V"
"R36","200 OHM","TopLayer","RESC1608X55X30NL15T15","334.646","-19.685","90","ERJ-3EKF2000V"
"R35","200 OHM","TopLayer","RESC1608X55X30NL15T15","265.748","-19.685","90","ERJ-3EKF2000V"
"R34","49.9R","TopLayer","RESC1608X55X25NL10T15","568.898","-3169.291","180","General Purpose Chip Resistor, 49.9 Ohm, +/- 1%, -55 to 155 degC, 0603 (1608 Metric), RoHS, Tape and Reel"
"R33","49.9R","TopLayer","RESC1608X55X25NL10T15","580.709","-2106.299","180","General Purpose Chip Resistor, 49.9 Ohm, +/- 1%, -55 to 155 degC, 0603 (1608 Metric), RoHS, Tape and Reel"
"R32","4.7K","TopLayer","RESC1608X55X30NL15T15","748.032","-3326.772","270","Precision Thick Film Chip Resistor, 4.7 KOhm, +/- 1%, -55 to 155 degC, 0603 (1608 Metric), RoHS, Tape and Reel ERJ-3EKF4701V"
"R31","4.7K","TopLayer","RESC1608X55X30NL15T15","826.772","-3326.772","270","Precision Thick Film Chip Resistor, 4.7 KOhm, +/- 1%, -55 to 155 degC, 0603 (1608 Metric), RoHS, Tape and Reel ERJ-3EKF4701V"
"P3","EXT GPIO","TopLayer","HDR2X6_CEN","5640.551","89.370","180","Header, 6-Pin, Dual row"
"J4","1909763-1","TopLayer","TECO-1909763-1_V","412.894","-3169.291","270","Ultra Miniature Coaxial Connector Jack, 60 V, 50 Ohm, -40 to 90 degC, RoHS, Tape and Reel"
"J2","1909763-1","TopLayer","TECO-1909763-1_V","412.894","-2106.299","270","Ultra Miniature Coaxial Connector Jack, 60 V, 50 Ohm, -40 to 90 degC, RoHS, Tape and Reel"
"J3","1909763-1","TopLayer","TECO-1909763-1_V","412.894","-2627.953","270","Ultra Miniature Coaxial Connector Jack, 60 V, 50 Ohm, -40 to 90 degC, RoHS, Tape and Reel"
"J1","1909763-1","TopLayer","TECO-1909763-1_V","412.894","-1574.803","270","Ultra Miniature Coaxial Connector Jack, 60 V, 50 Ohm, -40 to 90 degC, RoHS, Tape and Reel"
"D18","155124M173200","TopLayer","155124M173200","-190.453","-3413.386","90","LED (Multiple)"
"D17","155124M173200","TopLayer","155124M173200","-190.453","-2885.827","90","LED (Multiple)"
"D16","155124M173200","TopLayer","155124M173200","-190.453","-2350.394","90","LED (Multiple)"
"D15","155124M173200","TopLayer","155124M173200","-190.453","-1822.835","90","LED (Multiple)"
"C40","0.1uF","TopLayer","CAPC1608X87X45ML20T05","826.772","-1259.843","90","C0603X104K5RACAUTO"
"C39","0.1uF","TopLayer","CAPC1608X87X45ML20T05","758.445","-1137.402","270","C0603X104K5RACAUTO"
"C38","1uF","TopLayer","FP-C0603C105K3PACTU-MFG","757.874","-1253.937","270","CAP CER 1UF 25V X5R 0603"
"C33","0.1uF","TopLayer","CAPC1608X87X45ML20T05","5000.000","-1348.913","90","C0603X104K5RACAUTO"
"C32","0.1uF","TopLayer","CAPC1608X87X45ML20T05","4844.488","-1376.472","180","C0603X104K5RACAUTO"
"R37","10K","TopLayer","RESC1608X55X30LL15T20","4586.614","-1376.472","180","Chip Resistor, 10 KOhm, +/- 1%, 0.1 W, -55 to 155 degC, 0603 (1608 Metric), RoHS, Tape and Reel RMCF0603FT10K0"
"U15","RCB-F9T-1","TopLayer","GNSS","6406.398","-258.362","180","MOD, GPS"
"C37","0.1uF","TopLayer","CAPC1608X87X45ML20T05","6474.409","-500.488","0","C0603X104K5RACAUTO"
"C36","0.1uF","TopLayer","CAPC1608X87X45ML20T05","6127.664","-140.170","0","C0603X104K5RACAUTO"
"C35","10uF","TopLayer","FP-MK212BG-MFG","6476.378","-589.071","180","None"
"C34","10uF","TopLayer","FP-MK212BG-MFG","6131.890","-215.055","180","None"
"D2","8240136","TopLayer","SOT143-4L","344.488","-2874.016","90","TVS Diode WE-TVS-HS, VRWM=3.3V"
"D1","8240136","TopLayer","SOT143-4L","344.488","-1797.244","90","TVS Diode WE-TVS-HS, VRWM=3.3V"
"R27","4.7K","TopLayer","RESC1608X55X30NL15T15","3996.063","-1317.417","90","Precision Thick Film Chip Resistor, 4.7 KOhm, +/- 1%, -55 to 155 degC, 0603 (1608 Metric), RoHS, Tape and Reel ERJ-3EKF4701V"
"R26","4.7K","TopLayer","RESC1608X55X30NL15T15","4055.118","-1317.417","90","Precision Thick Film Chip Resistor, 4.7 KOhm, +/- 1%, -55 to 155 degC, 0603 (1608 Metric), RoHS, Tape and Reel ERJ-3EKF4701V"
"U10","MAC-SA5X","TopLayer","SA53","2258.562","-2419.291","180","MOD, MAC, MAC-SA5X, ATOMIC CLOCK"
"R14","4.7K","TopLayer","RESC1608X55X30NL15T15","826.772","-1722.441","270","Precision Thick Film Chip Resistor, 4.7 KOhm, +/- 1%, -55 to 155 degC, 0603 (1608 Metric), RoHS, Tape and Reel ERJ-3EKF4701V"
"U14","BME280","TopLayer","FP-BME280-MFG","5157.480","-1248.520","0","SENSOR PRESSURE HUMIDITY TEMP"
"U13","BMX160","TopLayer","FP-BMX160-MFG","4862.205","-1248.520","0","IMU ACCEL/GYRO/MAG"
"U4","DS90LV028AQMA","TopLayer","M08A_L","2185.039","-1218.992","0","Automotive LVDS Dual Differential Line Receiver, 8-pin Narrow SOIC"
"U3","DS90LV027AQMA","TopLayer","M08A_N","2889.764","-1214.465","0","Automotive LVDS Dual Differential Driver, 8-pin Narrow SOIC"
"R25","49.9R","TopLayer","RESC1608X55X25NL10T15","570.866","-1574.803","180","General Purpose Chip Resistor, 49.9 Ohm, +/- 1%, -55 to 155 degC, 0603 (1608 Metric), RoHS, Tape and Reel"
"R17","4.7K","TopLayer","RESC1608X55X30NL15T15","757.874","-2785.433","270","Precision Thick Film Chip Resistor, 4.7 KOhm, +/- 1%, -55 to 155 degC, 0603 (1608 Metric), RoHS, Tape and Reel ERJ-3EKF4701V"
"R13","49.9R","TopLayer","RESC1608X55X25NL10T15","2372.047","-1228.835","270","General Purpose Chip Resistor, 49.9 Ohm, +/- 1%, -55 to 155 degC, 0603 (1608 Metric), RoHS, Tape and Reel"
"R12","110R","TopLayer","RESC1609X50X30NL10T20","1998.032","-1169.780","270",""
"R11","4.7K","TopLayer","RESC1608X55X25LL10T15","2647.638","-1268.205","0","Chip Resistor, 4.7 KOhm, +/- 1%, 0.1 W, -55 to 155 degC, 0603 (1608 Metric), RoHS, Tape and Reel RC0603FR-074K7L"
"R10","4.7K","TopLayer","RESC1608X55X25LL10T15","2647.638","-1189.465","0","Chip Resistor, 4.7 KOhm, +/- 1%, 0.1 W, -55 to 155 degC, 0603 (1608 Metric), RoHS, Tape and Reel RC0603FR-074K7L"
"C31","0.1uF","TopLayer","CAPC1608X87X45ML20T05","5285.433","-1148.126","270","C0603X104K5RACAUTO"
"C30","0.1uF","TopLayer","CAPC1608X87X45ML20T05","5159.449","-1120.567","180","C0603X104K5RACAUTO"
"C29","0.1uF","TopLayer","CAPC1608X87X45ML20T05","679.134","-3326.772","270","C0603X104K5RACAUTO"
"C28","0.1uF","TopLayer","CAPC1608X87X45ML20T05","688.976","-2244.094","270","C0603X104K5RACAUTO"
"C27","0.1uF","TopLayer","CAPC1608X87X45ML20T05","688.976","-2785.433","270","C0603X104K5RACAUTO"
"C26","0.1uF","TopLayer","CAPC1608X87X45ML20T05","679.134","-1722.441","270","C0603X104K5RACAUTO"
"C24","0.1uF","TopLayer","CAPC1608X87X45ML20T05","2440.945","-1179.622","270","C0603X104K5RACAUTO"
"C23","0.1uF","TopLayer","CAPC1608X87X45ML20T05","2667.323","-1120.567","0","C0603X104K5RACAUTO"
"AN1","901-143-6RFX","TopLayer","AMPH-901-143-6RFX_V","-84.645","-1573.323","180","Coaxial connector, 50 Ohm, -65 to 165 degC, 5-Pin THD, RoHS, Bulk"
"AN3","901-143-6RFX","TopLayer","AMPH-901-143-6RFX_V","-84.646","-2636.299","180","Coaxial connector, 50 Ohm, -65 to 165 degC, 5-Pin THD, RoHS, Bulk"
"AN2","901-143-6RFX","TopLayer","AMPH-901-143-6RFX_V","-84.646","-2104.803","180","Coaxial connector, 50 Ohm, -65 to 165 degC, 5-Pin THD, RoHS, Bulk"
"AN4","901-143-6RFX","TopLayer","AMPH-901-143-6RFX_V","-84.645","-3167.811","180","Coaxial connector, 50 Ohm, -65 to 165 degC, 5-Pin THD, RoHS, Bulk"
"U7","AT24MAC402-STUM-T","TopLayer","FP-5TS1-IPC_C","4606.299","-1258.362","270","IC EEPROM 2K I2C 1MHZ SOT23-5"
"C25","0.1uF","TopLayer","CAPC1608X87X45ML20T05","4478.346","-1258.362","270","C0603X104K5RACAUTO"
"R16","4.7K","TopLayer","RESC1608X55X30NL15T15","836.614","-2785.433","270","Precision Thick Film Chip Resistor, 4.7 KOhm, +/- 1%, -55 to 155 degC, 0603 (1608 Metric), RoHS, Tape and Reel ERJ-3EKF4701V"
"R15","4.7K","TopLayer","RESC1608X55X30NL15T15","748.032","-1722.441","270","Precision Thick Film Chip Resistor, 4.7 KOhm, +/- 1%, -55 to 155 degC, 0603 (1608 Metric), RoHS, Tape and Reel ERJ-3EKF4701V"
"R5","ERJ-3EKF2612V","TopLayer","RESC1608X50N","5738.134","-1172.055","0","RES, 26.1K, 1%, 1/10W, TF, 0603"
"U9","RCB-F9T","TopLayer","GNSS","827.855","-618.598","0","MOD, GPS"
"U5","HTST-105-01-L-DV-A","TopLayer","SAMTEC_HTST-105-01-L-DV-A","5892.913","-3300.394","0","CONN, HDR, 2X5, VERT, 0.1IN  SHROUDED, SMT, HTSH SERIES"
"U2","MP1482DS-LF","TopLayer","SOIC127P600X175-8N","5593.134","-1304.055","90","IC, DC/DC, MP1482DS, >4.75VIN, 0.923-15V OUT, SOIC8"
"U1","MP1482DS-LF","TopLayer","SOIC127P600X175-8N","5684.189","-2334.055","90","IC, DC/DC, MP1482DS, >4.75VIN, 0.923-15V OUT, SOIC8"
"R30","4.7K","TopLayer","RESC1608X55X30NL15T15","757.874","-2244.094","270","Precision Thick Film Chip Resistor, 4.7 KOhm, +/- 1%, -55 to 155 degC, 0603 (1608 Metric), RoHS, Tape and Reel ERJ-3EKF4701V"
"R29","4.7K","TopLayer","RESC1608X55X30NL15T15","826.772","-2244.095","270","Precision Thick Film Chip Resistor, 4.7 KOhm, +/- 1%, -55 to 155 degC, 0603 (1608 Metric), RoHS, Tape and Reel ERJ-3EKF4701V"
"R28","49.9R","TopLayer","RESC1608X55X25NL10T15","580.709","-2627.953","180","General Purpose Chip Resistor, 49.9 Ohm, +/- 1%, -55 to 155 degC, 0603 (1608 Metric), RoHS, Tape and Reel"
"R24","ERJ-2GE0R00X","TopLayer","RESC1005X04N","2769.685","-3561.512","270","RES, 0. OHM, 1%, 1/16W, TF, AEC-Q200, 0402"
"R23","ERJ-2GE0R00X","TopLayer","RESC1005X04N","2218.504","-3561.512","270","RES, 0. OHM, 1%, 1/16W, TF, AEC-Q200, 0402"
"R22","ERJ-3EKF4701V","TopLayer","RESC1608X50N","1134.252","-2636.315","180","RES, 4.7K, 1%, 1/10W, TF, 0603"
"R21","CRCW080533R0FKEA","TopLayer","RESC2012X50N","6370.079","-3429.134","270","RES, 33 OHM, 1%, 1/8W, TF, 0805"
"R20","CRCW080533R0FKEA","TopLayer","RESC2012X50N","6551.181","-3425.197","270","RES, 33 OHM, 1%, 1/8W, TF, 0805"
"R19","CRCW080533R0FKEA","TopLayer","RESC2012X50N","5361.624","-3478.796","0","RES, 33 OHM, 1%, 1/8W, TF, 0805"
"R18","CRCW080533R0FKEA","TopLayer","RESC2012X50N","5365.561","-3317.379","0","RES, 33 OHM, 1%, 1/8W, TF, 0805"
"R9","ERJ-3EKF2201V","TopLayer","RESC1608X50N","5639.275","-1053.150","180","RES, 2.2K, 1%, 1/10W, TF, 0603"
"R8","ERJ-3EKF2201V","TopLayer","RESC1608X50N","5734.740","-2068.898","180","RES, 2.2K, 1%, 1/10W, TF, 0603"
"R7","ERJ-3EKF1002V","TopLayer","RESC1608X50N","5737.701","-1387.795","90","RES, 10K, 1%, 1/10W, TF, 0603"
"R6","ERJ-3EKF1002V","TopLayer","RESC1608X50N","5821.354","-2305.118","90","RES, 10K, 1%, 1/10W, TF, 0603"
"R4","ERJ-3EKF4702V","TopLayer","RESC1608X50N","5824.189","-2199.055","90","RES, 47K, 1%, 1/10W, TF, 0603"
"R3","ERJ-3EKF4702V","TopLayer","RESC1608X50N","5433.134","-1284.055","180","RES, 47K, 1%, 1/10W, TF, 0603"
"R2","ERJ-3EKF4702V","TopLayer","RESC1608X50N","5524.189","-2319.055","180","RES, 47K, 1%, 1/10W, TF, 0603"
"R1","ERJ-3EKF2000V","TopLayer","RESC1608X50N","6210.142","-1183.071","0","RES, 200 OHM, 1%, 1/10W, TF, 0603"
"P2","PCIex4","TopLayer","PCIE_4LANE_EDGE","2161.417","-4004.518","0","PCIE x4 Edge Connector,OrCAD Symbol,NC"
"L2","PM124SH-100M-RC","TopLayer","IND_PM124SH","5818.898","-1736.220","180","IND, PWR, 10.uH, 20%, 4A, 0.04DCR, 12.5X12.5MM, SHLD"
"L1","PM124SH-100M-RC","TopLayer","IND_PM124SH","5989.189","-2749.055","180","IND, PWR, 10.uH, 20%, 4A, 0.04DCR, 12.5X12.5MM, SHLD"
"F1","FUSE_0603_2.00A","TopLayer","FUSM1608X60N","6515.748","-2496.063","180","FUSE SLOW 2.00A 32V M 0603"
"D14","155124M173200","TopLayer","155124M173200","-190.453","-1084.646","90","LED (Multiple)"
"D13","155124M173200","TopLayer","155124M173200","-190.453","-651.575","90","LED (Multiple)"
"D11","BLUE","TopLayer","FP-LTST-C191TBKT-MFG","472.441","118.110","90","LED BLUE CLEAR CHIP SMD"
"D8","BAT54SW","TopLayer","SOT65P210X110-3N","6370.079","-3248.032","270","DIO, SCHOTTKY, BAT54S, DUAL SERIES, 30V, 200MA, SC-70"
"D7","BAT54SW","TopLayer","SOT65P210X110-3N","6557.087","-3249.016","270","DIO, SCHOTTKY, BAT54S, DUAL SERIES, 30V, 200MA, SC-70"
"D6","BAT54SW","TopLayer","SOT65P210X110-3N","5195.286","-3478.796","0","DIO, SCHOTTKY, BAT54S, DUAL SERIES, 30V, 200MA, SC-70"
"D5","BAT54SW","TopLayer","SOT65P210X110-3N","5196.270","-3317.379","0","DIO, SCHOTTKY, BAT54S, DUAL SERIES, 30V, 200MA, SC-70"
"D4","RED","TopLayer","DIOM1608X06N","6208.661","-1244.094","180","LED, RED, SML-LX0603, 635NM, 2V, 20MA, 0603"
"C63","0.1uF","TopLayer","CAPC1608X87X45ML20T05","3481.060","-1014.822","270","C0603X104K5RACAUTO"
"C62","CAP_0805_10UF_25V","TopLayer","CAPC2012X14N","3574.803","-1003.937","90","CAP, CER, 10.UF, 25V, 10%, X5R, 0805"
"C61","0.1uF","TopLayer","CAPC1608X87X45ML20T05","984.252","-953.244","90","C0603X104K5RACAUTO"
"C60","10uF","TopLayer","FP-MK212BG-MFG","895.669","-943.402","270","None"
"C59","0.1uF","TopLayer","CAPC1608X87X45ML20T05","1141.732","-766.236","90","C0603X104K5RACAUTO"
"C58","10uF","TopLayer","FP-MK212BG-MFG","1230.315","-760.331","270","None"
"C53","CAP_0402_0.1UF_50V","BottomLayer","CAPC1005X06N","2734.410","-3806.000","90","CAP, CER, 0.1UF, 50V, 10%, X7R, AEC-Q200, 0402"
"C52","CAP_0402_0.1UF_50V","BottomLayer","CAPC1005X06N","2694.410","-3806.000","90","CAP, CER, 0.1UF, 50V, 10%, X7R, AEC-Q200, 0402"
"C51","CAP_0402_0.1UF_50V","BottomLayer","CAPC1005X06N","2569.410","-3806.000","90","CAP, CER, 0.1UF, 50V, 10%, X7R, AEC-Q200, 0402"
"C50","CAP_0402_0.1UF_50V","BottomLayer","CAPC1005X06N","2534.410","-3806.000","90","CAP, CER, 0.1UF, 50V, 10%, X7R, AEC-Q200, 0402"
"C49","CAP_0402_0.1UF_50V","BottomLayer","CAPC1005X06N","2419.410","-3806.000","90","CAP, CER, 0.1UF, 50V, 10%, X7R, AEC-Q200, 0402"
"C48","CAP_0402_0.1UF_50V","BottomLayer","CAPC1005X06N","2379.410","-3806.000","90","CAP, CER, 0.1UF, 50V, 10%, X7R, AEC-Q200, 0402"
"C47","CAP_0402_0.1UF_50V","BottomLayer","CAPC1005X06N","2226.410","-3806.000","90","CAP, CER, 0.1UF, 50V, 10%, X7R, AEC-Q200, 0402"
"C46","CAP_0402_0.1UF_50V","BottomLayer","CAPC1005X06N","2183.410","-3806.000","90","CAP, CER, 0.1UF, 50V, 10%, X7R, AEC-Q200, 0402"
"C45","CAP_0402_0.1UF_50V","BottomLayer","CAPC1005X06N","2104.410","-3806.000","90","CAP, CER, 0.1UF, 50V, 10%, X7R, AEC-Q200, 0402"
"C44","CAP_0402_0.1UF_50V","BottomLayer","CAPC1005X06N","2064.410","-3806.000","90","CAP, CER, 0.1UF, 50V, 10%, X7R, AEC-Q200, 0402"
"C22","0.033uF","TopLayer","CAPC1608X90X35NL10T15","5638.134","-1114.055","0","GCM188R71H333KA55D"
"C21","0.1uF","TopLayer","CAPC1608X87X45ML20T05","5448.134","-1174.055","270","C0603X104K5RACAUTO"
"C20","0.033uF","TopLayer","CAPC1608X90X35NL10T15","5734.189","-2129.055","0","GCM188R71H333KA55D"
"C19","0.1uF","TopLayer","CAPC1608X87X45ML20T05","5544.189","-2194.055","270","C0603X104K5RACAUTO"
"C18","0.1uF","TopLayer","CAPC1608X87X45ML20T05","5864.189","-2409.055","90","C0603X104K5RACAUTO"
"C17","0.1uF","TopLayer","CAPC1608X87X45ML20T05","5919.189","-2409.055","90","C0603X104K5RACAUTO"
"C16","0.1uF","TopLayer","CAPC1608X87X45ML20T05","5969.189","-2409.055","90","C0603X104K5RACAUTO"
"C15","0.1uF","TopLayer","CAPC1608X87X45ML20T05","6029.189","-2409.055","90","C0603X104K5RACAUTO"
"C14","CAP_0805_10UF_25V","TopLayer","CAPC2012X14N","6109.189","-2404.055","270","CAP, CER, 10.UF, 25V, 10%, X5R, 0805"
"C13","CAP_0805_10UF_25V","TopLayer","CAPC2012X14N","6219.189","-2404.055","270","CAP, CER, 10.UF, 25V, 10%, X5R, 0805"
"C12","0.1uF","TopLayer","CAPC1608X87X45ML20T05","5950.299","-1391.733","90","C0603X104K5RACAUTO"
"C11","0.1uF","TopLayer","CAPC1608X87X45ML20T05","5883.370","-1391.733","90","C0603X104K5RACAUTO"
"C10","0.1uF","TopLayer","CAPC1608X87X45ML20T05","5812.504","-1391.733","90","C0603X104K5RACAUTO"
"C9","0.1uF","TopLayer","CAPC1608X87X45ML20T05","6017.228","-1391.733","90","C0603X104K5RACAUTO"
"C8","CAP_0805_10UF_25V","TopLayer","CAPC2012X14N","6229.827","-1411.417","0","CAP, CER, 10.UF, 25V, 10%, X5R, 0805"
"C7","CAP_0805_10UF_25V","TopLayer","CAPC2012X14N","6229.827","-1324.803","0","CAP, CER, 10.UF, 25V, 10%, X5R, 0805"
"C6","CAP_0805_10UF_25V","TopLayer","CAPC2012X14N","5509.189","-2409.055","180","CAP, CER, 10.UF, 25V, 10%, X5R, 0805"
"C5","CAP_0805_10UF_25V","TopLayer","CAPC2012X14N","5423.134","-1384.055","180","CAP, CER, 10.UF, 25V, 10%, X5R, 0805"
"C4","CAP_0603_0.01UF_50V","TopLayer","CAPC1608X10N","5654.189","-2549.055","0","CAP, CER, 0.01UF, 50V, 10%, X7R, 0603"
"C3","CAP_0603_0.01UF_50V","TopLayer","CAPC1608X10N","5484.252","-1539.370","270","CAP, CER, 0.01UF, 50V, 10%, X7R, 0603"
"C2","0.1uF","TopLayer","CAPC1608X87X45ML20T05","6397.638","-2389.764","270","C0603X104K5RACAUTO"
"C1","CAP_0805_10UF_25V","TopLayer","CAPC2012X14N","6484.252","-2377.953","90","CAP, CER, 10.UF, 25V, 10%, X5R, 0805"
